(kicad_pcb
	(version 20260206)
	(generator "pcbnew")
	(generator_version "10.0")
	(general
		(thickness 1.6)
		(legacy_teardrops no)
	)
	(paper "A4")
	(title_block
		(title "timecard-production-celestica-r4006 — R4006-B0001-02_R01.brd")
		(comment 1 "Time Appliance Project (Time Card) / footprints 78-85 of 1113")
	)
	(layers
		(0 "F.Cu" signal "TOP")
		(4 "In1.Cu" signal "L02_GND1")
		(6 "In2.Cu" signal "L03_SIG1")
		(8 "In3.Cu" signal "L04_GND2")
		(10 "In4.Cu" signal "L05_VCC1")
		(12 "In5.Cu" signal "L06_VCC2")
		(14 "In6.Cu" signal "L07_GND3")
		(16 "In7.Cu" signal "L08_SIG2")
		(18 "In8.Cu" signal "L09_GND4")
		(2 "B.Cu" signal "BOTTOM")
		(9 "F.Adhes" user "F.Adhesive")
		(11 "B.Adhes" user "B.Adhesive")
		(13 "F.Paste" user "Package Geometry/Pastemask Top")
		(15 "B.Paste" user "Package Geometry/Pastemask Bottom")
		(5 "F.SilkS" user "Ref Des/Silkscreen Top")
		(7 "B.SilkS" user "Ref Des/Silkscreen Bottom")
		(1 "F.Mask" user "Board Geometry/Soldermask Top")
		(3 "B.Mask" user "Board Geometry/Soldermask Bottom")
		(17 "Dwgs.User" user "User.Drawings")
		(19 "Cmts.User" user "User.Comments")
		(21 "Eco1.User" user "User.Eco1")
		(23 "Eco2.User" user "User.Eco2")
		(25 "Edge.Cuts" user "Board Geometry/Outline")
		(27 "Margin" user)
		(31 "F.CrtYd" user "Package Geometry/Place Bound Top")
		(29 "B.CrtYd" user "Package Geometry/Place Bound Bottom")
		(35 "F.Fab" user "Ref Des/Assembly Top")
		(33 "B.Fab" user "Ref Des/Assembly Bottom")
	)
	(footprint ""
		(layer "F.Cu")
		(at 143.256 -24.511 -90)
		(property "Reference" "C226"
			(at -3.429 0.08763 90)
			(unlocked yes)
			(layer "F.SilkS")
			(effects
				(font
					(size 0.7874 0.5842)
					(thickness 0.1524)
				)
			)
		)
		(property "Value" "VAL*"
			(at 0.0762 2.067306 270)
			(unlocked yes)
			(layer "F.Fab")
			(hide yes)
			(effects
				(font
					(size 0.7874 0.5842)
					(thickness 0.1524)
				)
			)
		)
		(property "Tolerance" "TOL*"
			(at 0.0762 3.032506 270)
			(unlocked yes)
			(layer "Cmts.User")
			(hide yes)
			(effects
				(font
					(size 0.7874 0.5842)
					(thickness 0.1524)
				)
			)
		)
		(property "User Part Number" "PARTNUM*"
			(at 0.1016 4.023106 270)
			(unlocked yes)
			(layer "Cmts.User")
			(hide yes)
			(effects
				(font
					(size 0.7874 0.5842)
					(thickness 0.1524)
				)
			)
		)
		(property "Device Type" "CAPACITOR-G105-0B104-EK,0.1UF,A"
			(at 0.0508 1.127506 270)
			(unlocked yes)
			(layer "F.Fab")
			(hide yes)
			(effects
				(font
					(size 0.7874 0.5842)
					(thickness 0.1524)
				)
			)
		)
		(duplicate_pad_numbers_are_jumpers no)
		(fp_line
			(start -1.143 0.5588)
			(end 1.143 0.5588)
			(stroke
				(width 0.1)
				(type default)
			)
			(layer "F.SilkS")
		)
		(fp_line
			(start 1.143 0.5588)
			(end 1.143 -0.5588)
			(stroke
				(width 0.1)
				(type default)
			)
			(layer "F.SilkS")
		)
		(fp_line
			(start -1.143 -0.5588)
			(end -1.143 0.5588)
			(stroke
				(width 0.1)
				(type default)
			)
			(layer "F.SilkS")
		)
		(fp_line
			(start 1.143 -0.5588)
			(end -1.143 -0.5588)
			(stroke
				(width 0.1)
				(type default)
			)
			(layer "F.SilkS")
		)
		(fp_rect
			(start -1.143 0.5588)
			(end 1.143 -0.5588)
			(stroke
				(width 0)
				(type default)
			)
			(fill no)
			(layer "F.CrtYd")
		)
		(fp_line
			(start -0.508 0.3048)
			(end 0.508 0.3048)
			(stroke
				(width 0.1)
				(type default)
			)
			(layer "F.Fab")
		)
		(fp_line
			(start 0.508 0.3048)
			(end 0.508 -0.3048)
			(stroke
				(width 0.1)
				(type default)
			)
			(layer "F.Fab")
		)
		(fp_line
			(start -0.508 -0.3048)
			(end -0.508 0.3048)
			(stroke
				(width 0.1)
				(type default)
			)
			(layer "F.Fab")
		)
		(fp_line
			(start 0.508 -0.3048)
			(end -0.508 -0.3048)
			(stroke
				(width 0.1)
				(type default)
			)
			(layer "F.Fab")
		)
		(pad "1" smd rect
			(at -0.5334 0 270)
			(size 0.7112 0.6096)
			(layers "F.Cu" "F.Mask" "F.Paste")
			(net "XP3R3V")
		)
		(pad "2" smd rect
			(at 0.5334 0 270)
			(size 0.7112 0.6096)
			(layers "F.Cu" "F.Mask" "F.Paste")
			(net "SG")
		)
		(zone
			(layer "F.Cu")
			(hatch none 0.5)
			(connect_pads
				(clearance 0)
			)
			(min_thickness 0.25)
			(keepout
				(tracks allowed)
				(vias not_allowed)
				(pads allowed)
				(copperpour not_allowed)
				(footprints allowed)
			)
			(placement
				(enabled no)
				(sheetname "")
			)
			(fill
				(thermal_gap 0.5)
				(thermal_bridge_width 0.5)
				(island_removal_mode 0)
			)
			(polygon
				(pts
					(xy 142.9512 -24.5872) (xy 142.9512 -24.4348) (xy 143.5608 -24.4348) (xy 143.5608 -24.5872)
				)
			)
		)
	)
	(footprint ""
		(layer "F.Cu")
		(at 124.587 -42.545 180)
		(property "Reference" "R288"
			(at -3.048 1.35763 0)
			(unlocked yes)
			(layer "F.SilkS")
			(effects
				(font
					(size 0.7874 0.5842)
					(thickness 0.1524)
				)
			)
		)
		(property "Value" "VAL*"
			(at 0.02032 2.13233 180)
			(unlocked yes)
			(layer "F.Fab")
			(hide yes)
			(effects
				(font
					(size 0.7874 0.5842)
					(thickness 0.1524)
				)
			)
		)
		(property "Tolerance" "TOL*"
			(at 0.044704 3.05435 180)
			(unlocked yes)
			(layer "Cmts.User")
			(hide yes)
			(effects
				(font
					(size 0.7874 0.5842)
					(thickness 0.1524)
				)
			)
		)
		(property "User Part Number" "PARTNUM*"
			(at 0.02032 4.024884 180)
			(unlocked yes)
			(layer "Cmts.User")
			(hide yes)
			(effects
				(font
					(size 0.7874 0.5842)
					(thickness 0.1524)
				)
			)
		)
		(property "Device Type" "RESISTOR-G155-14701-01,4.7KOHMA"
			(at 0.008382 1.210564 180)
			(unlocked yes)
			(layer "F.Fab")
			(hide yes)
			(effects
				(font
					(size 0.7874 0.5842)
					(thickness 0.1524)
				)
			)
		)
		(duplicate_pad_numbers_are_jumpers no)
		(fp_line
			(start 1.143 0.5588)
			(end 1.143 -0.5588)
			(stroke
				(width 0.1)
				(type default)
			)
			(layer "F.SilkS")
		)
		(fp_line
			(start 1.143 -0.5588)
			(end -1.143 -0.5588)
			(stroke
				(width 0.1)
				(type default)
			)
			(layer "F.SilkS")
		)
		(fp_line
			(start -1.143 0.5588)
			(end 1.143 0.5588)
			(stroke
				(width 0.1)
				(type default)
			)
			(layer "F.SilkS")
		)
		(fp_line
			(start -1.143 -0.5588)
			(end -1.143 0.5588)
			(stroke
				(width 0.1)
				(type default)
			)
			(layer "F.SilkS")
		)
		(fp_rect
			(start 1.143 0.5588)
			(end -1.143 -0.5588)
			(stroke
				(width 0)
				(type default)
			)
			(fill no)
			(layer "F.CrtYd")
		)
		(fp_line
			(start 0.508 0.3048)
			(end 0.508 -0.3048)
			(stroke
				(width 0.1)
				(type default)
			)
			(layer "F.Fab")
		)
		(fp_line
			(start 0.508 -0.3048)
			(end -0.508 -0.3048)
			(stroke
				(width 0.1)
				(type default)
			)
			(layer "F.Fab")
		)
		(fp_line
			(start -0.508 0.3048)
			(end 0.508 0.3048)
			(stroke
				(width 0.1)
				(type default)
			)
			(layer "F.Fab")
		)
		(fp_line
			(start -0.508 -0.3048)
			(end -0.508 0.3048)
			(stroke
				(width 0.1)
				(type default)
			)
			(layer "F.Fab")
		)
		(pad "1" smd rect
			(at -0.5334 0 180)
			(size 0.7112 0.6096)
			(layers "F.Cu" "F.Mask" "F.Paste")
			(net "SG")
		)
		(pad "2" smd rect
			(at 0.5334 0 180)
			(size 0.7112 0.6096)
			(layers "F.Cu" "F.Mask" "F.Paste")
			(net "FPGA_IN_MAC_BITEOUT")
		)
		(zone
			(layer "F.Cu")
			(hatch none 0.5)
			(connect_pads
				(clearance 0)
			)
			(min_thickness 0.25)
			(keepout
				(tracks allowed)
				(vias not_allowed)
				(pads allowed)
				(copperpour not_allowed)
				(footprints allowed)
			)
			(placement
				(enabled no)
				(sheetname "")
			)
			(fill
				(thermal_gap 0.5)
				(thermal_bridge_width 0.5)
				(island_removal_mode 0)
			)
			(polygon
				(pts
					(xy 124.5108 -42.8498) (xy 124.5108 -42.2402) (xy 124.6632 -42.2402) (xy 124.6632 -42.8498)
				)
			)
		)
	)
	(footprint ""
		(layer "F.Cu")
		(at 41.656 -132.461)
		(property "Reference" "SP36"
			(at 0 0 0)
			(layer "F.SilkS")
			(hide yes)
			(effects
				(font
					(size 1.27 1.27)
				)
			)
		)
		(property "Value" ""
			(at 0 0 0)
			(layer "F.Fab")
			(effects
				(font
					(size 1.27 1.27)
				)
			)
		)
		(duplicate_pad_numbers_are_jumpers no)
	)
	(footprint ""
		(layer "F.Cu")
		(at 90.2716 -44.868846 90)
		(property "Reference" "R266"
			(at -0.164846 -1.47193 90)
			(unlocked yes)
			(layer "F.SilkS")
			(effects
				(font
					(size 0.7874 0.5842)
					(thickness 0.1524)
				)
			)
		)
		(property "Value" "VAL*"
			(at 0.02032 2.13233 90)
			(unlocked yes)
			(layer "F.Fab")
			(hide yes)
			(effects
				(font
					(size 0.7874 0.5842)
					(thickness 0.1524)
				)
			)
		)
		(property "Device Type" "RESISTOR-G155-133R0-01,33OHM,1%"
			(at 0.008382 1.210564 90)
			(unlocked yes)
			(layer "F.Fab")
			(hide yes)
			(effects
				(font
					(size 0.7874 0.5842)
					(thickness 0.1524)
				)
			)
		)
		(property "User Part Number" "PARTNUM*"
			(at 0.02032 4.024884 90)
			(unlocked yes)
			(layer "Cmts.User")
			(hide yes)
			(effects
				(font
					(size 0.7874 0.5842)
					(thickness 0.1524)
				)
			)
		)
		(property "Tolerance" "TOL*"
			(at 0.044704 3.05435 90)
			(unlocked yes)
			(layer "Cmts.User")
			(hide yes)
			(effects
				(font
					(size 0.7874 0.5842)
					(thickness 0.1524)
				)
			)
		)
		(duplicate_pad_numbers_are_jumpers no)
		(fp_line
			(start 1.143 -0.5588)
			(end -1.143 -0.5588)
			(stroke
				(width 0.1)
				(type default)
			)
			(layer "F.SilkS")
		)
		(fp_line
			(start -1.143 -0.5588)
			(end -1.143 0.5588)
			(stroke
				(width 0.1)
				(type default)
			)
			(layer "F.SilkS")
		)
		(fp_line
			(start 1.143 0.5588)
			(end 1.143 -0.5588)
			(stroke
				(width 0.1)
				(type default)
			)
			(layer "F.SilkS")
		)
		(fp_line
			(start -1.143 0.5588)
			(end 1.143 0.5588)
			(stroke
				(width 0.1)
				(type default)
			)
			(layer "F.SilkS")
		)
		(fp_rect
			(start -1.143 -0.5588)
			(end 1.143 0.5588)
			(stroke
				(width 0)
				(type default)
			)
			(fill no)
			(layer "F.CrtYd")
		)
		(fp_line
			(start 0.508 -0.3048)
			(end -0.508 -0.3048)
			(stroke
				(width 0.1)
				(type default)
			)
			(layer "F.Fab")
		)
		(fp_line
			(start -0.508 -0.3048)
			(end -0.508 0.3048)
			(stroke
				(width 0.1)
				(type default)
			)
			(layer "F.Fab")
		)
		(fp_line
			(start 0.508 0.3048)
			(end 0.508 -0.3048)
			(stroke
				(width 0.1)
				(type default)
			)
			(layer "F.Fab")
		)
		(fp_line
			(start -0.508 0.3048)
			(end 0.508 0.3048)
			(stroke
				(width 0.1)
				(type default)
			)
			(layer "F.Fab")
		)
		(pad "1" smd rect
			(at -0.5334 0 90)
			(size 0.7112 0.6096)
			(layers "F.Cu" "F.Mask" "F.Paste")
			(net "RSVD_DBG_USB_MUX_SEL")
		)
		(pad "2" smd rect
			(at 0.5334 0 90)
			(size 0.7112 0.6096)
			(layers "F.Cu" "F.Mask" "F.Paste")
			(net "XP5R0V_USB_CONN_DET")
		)
		(zone
			(layer "F.Cu")
			(hatch none 0.5)
			(connect_pads
				(clearance 0)
			)
			(min_thickness 0.25)
			(keepout
				(tracks allowed)
				(vias not_allowed)
				(pads allowed)
				(copperpour not_allowed)
				(footprints allowed)
			)
			(placement
				(enabled no)
				(sheetname "")
			)
			(fill
				(thermal_gap 0.5)
				(thermal_bridge_width 0.5)
				(island_removal_mode 0)
			)
			(polygon
				(pts
					(xy 89.9668 -44.792646) (xy 90.5764 -44.792646) (xy 90.5764 -44.945046) (xy 89.9668 -44.945046)
				)
			)
		)
	)
	(footprint ""
		(layer "F.Cu")
		(at 47.244 -126.746)
		(property "Reference" "SP67"
			(at 0 0 0)
			(layer "F.SilkS")
			(hide yes)
			(effects
				(font
					(size 1.27 1.27)
				)
			)
		)
		(property "Value" ""
			(at 0 0 0)
			(layer "F.Fab")
			(effects
				(font
					(size 1.27 1.27)
				)
			)
		)
		(duplicate_pad_numbers_are_jumpers no)
	)
	(footprint ""
		(layer "F.Cu")
		(at 122.7074 -69.2912)
		(property "Reference" "TP40"
			(at -2.0066 -1.53543 0)
			(unlocked yes)
			(layer "F.SilkS")
			(effects
				(font
					(size 0.7874 0.5842)
					(thickness 0.1524)
				)
				(justify left)
			)
		)
		(property "Value" ""
			(at 0 0 0)
			(layer "F.Fab")
			(effects
				(font
					(size 1.27 1.27)
				)
			)
		)
		(property "Device Type" "TP_PIONT-TP010CT020B030_PTH-TPA"
			(at -1.341882 0.996696 0)
			(unlocked yes)
			(layer "F.Fab")
			(hide yes)
			(effects
				(font
					(size 0.7874 0.5842)
					(thickness 0.000001)
				)
				(justify left)
			)
		)
		(duplicate_pad_numbers_are_jumpers no)
		(fp_poly
			(pts
				(arc
					(start 0.889 0)
					(mid -0.889 0)
					(end 0.889 0)
				)
			)
			(stroke
				(width 0)
				(type default)
			)
			(fill no)
			(layer "B.CrtYd")
		)
		(fp_poly
			(pts
				(arc
					(start 0.889 0)
					(mid -0.889 0)
					(end 0.889 0)
				)
			)
			(stroke
				(width 0)
				(type default)
			)
			(fill no)
			(layer "F.CrtYd")
		)
		(pad "1" thru_hole circle
			(at 0 0)
			(size 0.508 0.508)
			(drill 0.254)
			(layers "*.Cu" "*.Mask")
			(remove_unused_layers no)
			(net "XP1R2V_FPGA_PG")
			(clearance 0.1016)
			(padstack
				(mode front_inner_back)
				(layer "Inner"
					(shape circle)
					(size 0.508 0.508)
					(clearance 0.1016)
				)
				(layer "B.Cu"
					(shape circle)
					(size 0.762 0.762)
					(clearance -0.0254)
				)
			)
		)
	)
	(footprint ""
		(layer "F.Cu")
		(at 135.001 -70.866 90)
		(property "Reference" "R182"
			(at 4.191 0.92837 90)
			(unlocked yes)
			(layer "F.SilkS")
			(effects
				(font
					(size 0.7874 0.5842)
					(thickness 0.1524)
				)
			)
		)
		(property "Value" "VAL*"
			(at 0.02032 2.13233 90)
			(unlocked yes)
			(layer "F.Fab")
			(hide yes)
			(effects
				(font
					(size 0.7874 0.5842)
					(thickness 0.1524)
				)
			)
		)
		(property "Device Type" "RESISTOR-G155-100R0-J0,0OHM,-"
			(at 0.008382 1.210564 90)
			(unlocked yes)
			(layer "F.Fab")
			(hide yes)
			(effects
				(font
					(size 0.7874 0.5842)
					(thickness 0.1524)
				)
			)
		)
		(property "User Part Number" "PARTNUM*"
			(at 0.02032 4.024884 90)
			(unlocked yes)
			(layer "Cmts.User")
			(hide yes)
			(effects
				(font
					(size 0.7874 0.5842)
					(thickness 0.1524)
				)
			)
		)
		(property "Tolerance" "TOL*"
			(at 0.044704 3.05435 90)
			(unlocked yes)
			(layer "Cmts.User")
			(hide yes)
			(effects
				(font
					(size 0.7874 0.5842)
					(thickness 0.1524)
				)
			)
		)
		(duplicate_pad_numbers_are_jumpers no)
		(fp_line
			(start 1.143 -0.5588)
			(end -1.143 -0.5588)
			(stroke
				(width 0.1)
				(type default)
			)
			(layer "F.SilkS")
		)
		(fp_line
			(start -1.143 -0.5588)
			(end -1.143 0.5588)
			(stroke
				(width 0.1)
				(type default)
			)
			(layer "F.SilkS")
		)
		(fp_line
			(start 1.143 0.5588)
			(end 1.143 -0.5588)
			(stroke
				(width 0.1)
				(type default)
			)
			(layer "F.SilkS")
		)
		(fp_line
			(start -1.143 0.5588)
			(end 1.143 0.5588)
			(stroke
				(width 0.1)
				(type default)
			)
			(layer "F.SilkS")
		)
		(fp_rect
			(start 1.143 0.5588)
			(end -1.143 -0.5588)
			(stroke
				(width 0)
				(type default)
			)
			(fill no)
			(layer "F.CrtYd")
		)
		(fp_line
			(start 0.508 -0.3048)
			(end -0.508 -0.3048)
			(stroke
				(width 0.1)
				(type default)
			)
			(layer "F.Fab")
		)
		(fp_line
			(start -0.508 -0.3048)
			(end -0.508 0.3048)
			(stroke
				(width 0.1)
				(type default)
			)
			(layer "F.Fab")
		)
		(fp_line
			(start 0.508 0.3048)
			(end 0.508 -0.3048)
			(stroke
				(width 0.1)
				(type default)
			)
			(layer "F.Fab")
		)
		(fp_line
			(start -0.508 0.3048)
			(end 0.508 0.3048)
			(stroke
				(width 0.1)
				(type default)
			)
			(layer "F.Fab")
		)
		(pad "1" smd rect
			(at -0.5334 0 90)
			(size 0.7112 0.6096)
			(layers "F.Cu" "F.Mask" "F.Paste")
			(net "XP1R8V_PG_R")
		)
		(pad "2" smd rect
			(at 0.5334 0 90)
			(size 0.7112 0.6096)
			(layers "F.Cu" "F.Mask" "F.Paste")
			(net "XP1R8V_FPGA_PG")
		)
		(zone
			(layer "F.Cu")
			(hatch none 0.5)
			(connect_pads
				(clearance 0)
			)
			(min_thickness 0.25)
			(keepout
				(tracks allowed)
				(vias not_allowed)
				(pads allowed)
				(copperpour not_allowed)
				(footprints allowed)
			)
			(placement
				(enabled no)
				(sheetname "")
			)
			(fill
				(thermal_gap 0.5)
				(thermal_bridge_width 0.5)
				(island_removal_mode 0)
			)
			(polygon
				(pts
					(xy 135.3058 -70.9422) (xy 134.6962 -70.9422) (xy 134.6962 -70.7898) (xy 135.3058 -70.7898)
				)
			)
		)
	)
	(footprint ""
		(layer "F.Cu")
		(at 120.396 -63.2206 90)
		(property "Reference" "C174"
			(at 3.8354 0.16637 90)
			(unlocked yes)
			(layer "F.SilkS")
			(effects
				(font
					(size 0.7874 0.5842)
					(thickness 0.1524)
				)
			)
		)
		(property "Value" "VAL*"
			(at 0.1016 3.769106 90)
			(unlocked yes)
			(layer "F.Fab")
			(hide yes)
			(effects
				(font
					(size 0.7874 0.5842)
					(thickness 0.1524)
				)
			)
		)
		(property "Device Type" "CAPACITOR-G109-0G107-BM,100UF,A"
			(at 0.0762 2.829306 90)
			(unlocked yes)
			(layer "F.Fab")
			(hide yes)
			(effects
				(font
					(size 0.7874 0.5842)
					(thickness 0.1524)
				)
			)
		)
		(property "User Part Number" "PARTNUM*"
			(at 0.2032 5.801106 90)
			(unlocked yes)
			(layer "Cmts.User")
			(hide yes)
			(effects
				(font
					(size 0.7874 0.5842)
					(thickness 0.1524)
				)
			)
		)
		(property "Tolerance" "TOL*"
			(at 0.127 4.734306 90)
			(unlocked yes)
			(layer "Cmts.User")
			(hide yes)
			(effects
				(font
					(size 0.7874 0.5842)
					(thickness 0.1524)
				)
			)
		)
		(duplicate_pad_numbers_are_jumpers no)
		(fp_line
			(start 2.159 -1.5748)
			(end 2.159 1.5748)
			(stroke
				(width 0.1)
				(type default)
			)
			(layer "F.SilkS")
		)
		(fp_line
			(start -2.159 -1.5748)
			(end 2.159 -1.5748)
			(stroke
				(width 0.1)
				(type default)
			)
			(layer "F.SilkS")
		)
		(fp_line
			(start 2.159 1.5748)
			(end -2.159 1.5748)
			(stroke
				(width 0.1)
				(type default)
			)
			(layer "F.SilkS")
		)
		(fp_line
			(start -2.159 1.5748)
			(end -2.159 -1.5748)
			(stroke
				(width 0.1)
				(type default)
			)
			(layer "F.SilkS")
		)
		(fp_rect
			(start -2.159 -1.5748)
			(end 2.159 1.5748)
			(stroke
				(width 0)
				(type default)
			)
			(fill no)
			(layer "F.CrtYd")
		)
		(fp_line
			(start 1.6002 -1.2446)
			(end -1.6002 -1.2446)
			(stroke
				(width 0.1)
				(type default)
			)
			(layer "F.Fab")
		)
		(fp_line
			(start -1.6002 -1.2446)
			(end -1.6002 1.2446)
			(stroke
				(width 0.1)
				(type default)
			)
			(layer "F.Fab")
		)
		(fp_line
			(start 1.6002 1.2446)
			(end 1.6002 -1.2446)
			(stroke
				(width 0.1)
				(type default)
			)
			(layer "F.Fab")
		)
		(fp_line
			(start -1.6002 1.2446)
			(end 1.6002 1.2446)
			(stroke
				(width 0.1)
				(type default)
			)
			(layer "F.Fab")
		)
		(pad "1" smd rect
			(at -1.3335 0 90)
			(size 1.143 2.6416)
			(layers "F.Cu" "F.Mask" "F.Paste")
			(net "XP3R3V_FPGA")
		)
		(pad "2" smd rect
			(at 1.3335 0 90)
			(size 1.143 2.6416)
			(layers "F.Cu" "F.Mask" "F.Paste")
			(net "SG")
		)
		(zone
			(layer "F.Cu")
			(hatch none 0.5)
			(connect_pads
				(clearance 0)
			)
			(min_thickness 0.25)
			(keepout
				(tracks allowed)
				(vias not_allowed)
				(pads allowed)
				(copperpour not_allowed)
				(footprints allowed)
			)
			(placement
				(enabled no)
				(sheetname "")
			)
			(fill
				(thermal_gap 0.5)
				(thermal_bridge_width 0.5)
				(island_removal_mode 0)
			)
			(polygon
				(pts
					(xy 118.999 -62.5348) (xy 121.793 -62.5348) (xy 121.793 -63.9064) (xy 118.999 -63.9064)
				)
			)
		)
	)
)
